# SCM (Grand Teton) — schematic netlist excerpt (pin names and nets, part order shuffled) for the footprints in the layout excerpt that follows; sources: Cadence DE-HDL packaged netlist, KiCad conversion of 12092022_DA0F0TMDCD0_F0T_Management_Board_D_brd_V3_OCP.brd

R60  Q_RES  33.2 1% CHIP  pkg 0402LF  page 13 : A = RST_ROT_CPU_R1_N ; B = RST_ROT_CPU_N
R683  Q_RES  4.7K 1% CHIP  pkg 0402LF  page 13 : A = P3V3_AUX ; B = PU_SPI1WP_N

(kicad_pcb
	(version 20260206)
	(generator "pcbnew")
	(generator_version "10.0")
	(general
		(thickness 1.6)
		(legacy_teardrops no)
	)
	(paper "A4")
	(title_block
		(title "12092022_DA0F0TMDCD0_F0T_Management_Board_D_brd_V3_OCP.brd")
		(comment 1 "Grand Teton / footprints 426-427 of 1440")
	)
	(layers
		(0 "F.Cu" signal "TOP")
		(4 "In1.Cu" signal "GND")
		(6 "In2.Cu" signal "IN1")
		(8 "In3.Cu" signal "GND1")
		(10 "In4.Cu" signal "IN2")
		(12 "In5.Cu" signal "VCC")
		(14 "In6.Cu" signal "VCC1")
		(16 "In7.Cu" signal "IN3")
		(18 "In8.Cu" signal "GND2")
		(20 "In9.Cu" signal "IN4")
		(22 "In10.Cu" signal "GND3")
		(2 "B.Cu" signal "BOTTOM")
		(9 "F.Adhes" user "F.Adhesive")
		(11 "B.Adhes" user "B.Adhesive")
		(13 "F.Paste" user "Package Geometry/Pastemask Top")
		(15 "B.Paste" user "Package Geometry/Pastemask Bottom")
		(5 "F.SilkS" user "Ref Des/Silkscreen Top")
		(7 "B.SilkS" user "Ref Des/Silkscreen Bottom")
		(1 "F.Mask" user "Board Geometry/Soldermask Top")
		(3 "B.Mask" user "Board Geometry/Soldermask Bottom")
		(17 "Dwgs.User" user "User.Drawings")
		(19 "Cmts.User" user "User.Comments")
		(21 "Eco1.User" user "User.Eco1")
		(23 "Eco2.User" user "User.Eco2")
		(25 "Edge.Cuts" user "Board Geometry/Outline")
		(27 "Margin" user)
		(31 "F.CrtYd" user "Package Geometry/Place Bound Top")
		(29 "B.CrtYd" user "Package Geometry/Place Bound Bottom")
		(35 "F.Fab" user "Ref Des/Assembly Top")
		(33 "B.Fab" user "Ref Des/Assembly Bottom")
	)
	(footprint ""
		(layer "F.Cu")
		(at 46.6852 -30.861 -90)
		(property "Reference" "R60"
			(at 0 0 270)
			(layer "F.SilkS")
			(hide yes)
			(effects
				(font
					(size 1.27 1.27)
				)
			)
		)
		(property "Value" ""
			(at 0 0 270)
			(layer "F.Fab")
			(effects
				(font
					(size 1.27 1.27)
				)
			)
		)
		(duplicate_pad_numbers_are_jumpers no)
		(fp_line
			(start -0.7874 0.4064)
			(end -0.7874 -0.4064)
			(stroke
				(width 0.1524)
				(type default)
			)
			(layer "F.SilkS")
		)
		(fp_line
			(start 0.7874 0.4064)
			(end -0.7874 0.4064)
			(stroke
				(width 0.1524)
				(type default)
			)
			(layer "F.SilkS")
		)
		(fp_line
			(start -0.7874 -0.4064)
			(end 0.7874 -0.4064)
			(stroke
				(width 0.1524)
				(type default)
			)
			(layer "F.SilkS")
		)
		(fp_line
			(start 0.7874 -0.4064)
			(end 0.7874 0.4064)
			(stroke
				(width 0.1524)
				(type default)
			)
			(layer "F.SilkS")
		)
		(fp_line
			(start -0.67945 0.3048)
			(end -0.67945 -0.305054)
			(stroke
				(width 0.1)
				(type default)
			)
			(layer "F.Fab")
		)
		(fp_line
			(start -0.12065 0.3048)
			(end -0.67945 0.3048)
			(stroke
				(width 0.1)
				(type default)
			)
			(layer "F.Fab")
		)
		(fp_line
			(start 0.120396 0.3048)
			(end 0.120396 0.2794)
			(stroke
				(width 0.1)
				(type default)
			)
			(layer "F.Fab")
		)
		(fp_line
			(start 0.67945 0.3048)
			(end 0.120396 0.3048)
			(stroke
				(width 0.1)
				(type default)
			)
			(layer "F.Fab")
		)
		(fp_line
			(start -0.12065 0.2794)
			(end -0.12065 0.3048)
			(stroke
				(width 0.1)
				(type default)
			)
			(layer "F.Fab")
		)
		(fp_line
			(start 0.120396 0.2794)
			(end -0.12065 0.2794)
			(stroke
				(width 0.1)
				(type default)
			)
			(layer "F.Fab")
		)
		(fp_line
			(start -0.12065 -0.2794)
			(end 0.12065 -0.2794)
			(stroke
				(width 0.1)
				(type default)
			)
			(layer "F.Fab")
		)
		(fp_line
			(start 0.12065 -0.2794)
			(end 0.12065 -0.3048)
			(stroke
				(width 0.1)
				(type default)
			)
			(layer "F.Fab")
		)
		(fp_line
			(start 0.12065 -0.3048)
			(end 0.67945 -0.3048)
			(stroke
				(width 0.1)
				(type default)
			)
			(layer "F.Fab")
		)
		(fp_line
			(start 0.67945 -0.3048)
			(end 0.67945 0.3048)
			(stroke
				(width 0.1)
				(type default)
			)
			(layer "F.Fab")
		)
		(fp_line
			(start -0.67945 -0.305054)
			(end -0.12065 -0.305054)
			(stroke
				(width 0.1)
				(type default)
			)
			(layer "F.Fab")
		)
		(fp_line
			(start -0.12065 -0.305054)
			(end -0.12065 -0.2794)
			(stroke
				(width 0.1)
				(type default)
			)
			(layer "F.Fab")
		)
		(pad "1" smd circle
			(at -0.40005 0 270)
			(size 0 0)
			(layers "F.Cu" "F.Mask" "F.Paste")
			(net "RST_ROT_CPU_R1_N")
		)
		(pad "2" smd circle
			(at 0.40005 0 270)
			(size 0 0)
			(layers "F.Cu" "F.Mask" "F.Paste")
			(net "RST_ROT_CPU_N")
		)
	)
	(footprint ""
		(layer "F.Cu")
		(at 58.7248 -65.5828)
		(property "Reference" "R683"
			(at 0 0 0)
			(layer "F.SilkS")
			(hide yes)
			(effects
				(font
					(size 1.27 1.27)
				)
			)
		)
		(property "Value" ""
			(at 0 0 0)
			(layer "F.Fab")
			(effects
				(font
					(size 1.27 1.27)
				)
			)
		)
		(duplicate_pad_numbers_are_jumpers no)
		(fp_line
			(start -0.7874 -0.4064)
			(end 0.7874 -0.4064)
			(stroke
				(width 0.1524)
				(type default)
			)
			(layer "F.SilkS")
		)
		(fp_line
			(start -0.7874 0.4064)
			(end -0.7874 -0.4064)
			(stroke
				(width 0.1524)
				(type default)
			)
			(layer "F.SilkS")
		)
		(fp_line
			(start 0.7874 -0.4064)
			(end 0.7874 0.4064)
			(stroke
				(width 0.1524)
				(type default)
			)
			(layer "F.SilkS")
		)
		(fp_line
			(start 0.7874 0.4064)
			(end -0.7874 0.4064)
			(stroke
				(width 0.1524)
				(type default)
			)
			(layer "F.SilkS")
		)
		(fp_line
			(start -0.67945 -0.305054)
			(end -0.12065 -0.305054)
			(stroke
				(width 0.1)
				(type default)
			)
			(layer "F.Fab")
		)
		(fp_line
			(start -0.67945 0.3048)
			(end -0.67945 -0.305054)
			(stroke
				(width 0.1)
				(type default)
			)
			(layer "F.Fab")
		)
		(fp_line
			(start -0.12065 -0.305054)
			(end -0.12065 -0.2794)
			(stroke
				(width 0.1)
				(type default)
			)
			(layer "F.Fab")
		)
		(fp_line
			(start -0.12065 -0.2794)
			(end 0.12065 -0.2794)
			(stroke
				(width 0.1)
				(type default)
			)
			(layer "F.Fab")
		)
		(fp_line
			(start -0.12065 0.2794)
			(end -0.12065 0.3048)
			(stroke
				(width 0.1)
				(type default)
			)
			(layer "F.Fab")
		)
		(fp_line
			(start -0.12065 0.3048)
			(end -0.67945 0.3048)
			(stroke
				(width 0.1)
				(type default)
			)
			(layer "F.Fab")
		)
		(fp_line
			(start 0.120396 0.2794)
			(end -0.12065 0.2794)
			(stroke
				(width 0.1)
				(type default)
			)
			(layer "F.Fab")
		)
		(fp_line
			(start 0.120396 0.3048)
			(end 0.120396 0.2794)
			(stroke
				(width 0.1)
				(type default)
			)
			(layer "F.Fab")
		)
		(fp_line
			(start 0.12065 -0.3048)
			(end 0.67945 -0.3048)
			(stroke
				(width 0.1)
				(type default)
			)
			(layer "F.Fab")
		)
		(fp_line
			(start 0.12065 -0.2794)
			(end 0.12065 -0.3048)
			(stroke
				(width 0.1)
				(type default)
			)
			(layer "F.Fab")
		)
		(fp_line
			(start 0.67945 -0.3048)
			(end 0.67945 0.3048)
			(stroke
				(width 0.1)
				(type default)
			)
			(layer "F.Fab")
		)
		(fp_line
			(start 0.67945 0.3048)
			(end 0.120396 0.3048)
			(stroke
				(width 0.1)
				(type default)
			)
			(layer "F.Fab")
		)
		(pad "1" smd circle
			(at -0.40005 0)
			(size 0 0)
			(layers "F.Cu" "F.Mask" "F.Paste")
			(net "P3V3_AUX")
		)
		(pad "2" smd circle
			(at 0.40005 0)
			(size 0 0)
			(layers "F.Cu" "F.Mask" "F.Paste")
			(net "PU_SPI1WP_N")
		)
	)
)
